# SA800U (Snapdragon 845) Baseboard — KiCad project settings (.kicad_pro: net classes, design rules, text variables)
{
  "board": {
    "design_settings": {
      "defaults": {
        "board_outline_line_width": 0.049999999999999996,
        "copper_line_width": 0.19999999999999998,
        "copper_text_italic": false,
        "copper_text_size_h": 1.5,
        "copper_text_size_v": 1.5,
        "copper_text_thickness": 0.3,
        "copper_text_upright": false,
        "courtyard_line_width": 0.049999999999999996,
        "dimension_precision": 4,
        "dimension_units": 3,
        "dimensions": {
          "arrow_length": 1270000,
          "extension_offset": 500000,
          "keep_text_aligned": true,
          "suppress_zeroes": false,
          "text_position": 0,
          "units_format": 1
        },
        "fab_line_width": 0.09999999999999999,
        "fab_text_italic": false,
        "fab_text_size_h": 1.0,
        "fab_text_size_v": 1.0,
        "fab_text_thickness": 0.15,
        "fab_text_upright": false,
        "other_line_width": 0.09999999999999999,
        "other_text_italic": false,
        "other_text_size_h": 1.0,
        "other_text_size_v": 1.0,
        "other_text_thickness": 0.15,
        "other_text_upright": false,
        "pads": {
          "drill": 0.0,
          "height": 6.15,
          "width": 6.15
        },
        "silk_line_width": 0.09999999999999999,
        "silk_text_italic": false,
        "silk_text_size_h": 0.65,
        "silk_text_size_v": 0.65,
        "silk_text_thickness": 0.15,
        "silk_text_upright": false,
        "zones": {
          "45_degree_only": false,
          "min_clearance": 0.127
        }
      },
      "diff_pair_dimensions": [
        {
          "gap": 0.0,
          "via_gap": 0.0,
          "width": 0.0
        }
      ],
      "drc_exclusions": [],
      "meta": {
        "filename": "board_design_settings.json",
        "version": 2
      },
      "rule_severities": {
        "annular_width": "error",
        "clearance": "error",
        "copper_edge_clearance": "error",
        "courtyards_overlap": "error",
        "diff_pair_gap_out_of_range": "error",
        "diff_pair_uncoupled_length_too_long": "error",
        "drill_out_of_range": "error",
        "duplicate_footprints": "warning",
        "extra_footprint": "warning",
        "footprint_type_mismatch": "error",
        "hole_clearance": "error",
        "hole_near_hole": "error",
        "invalid_outline": "error",
        "item_on_disabled_layer": "error",
        "items_not_allowed": "error",
        "length_out_of_range": "error",
        "malformed_courtyard": "error",
        "microvia_drill_out_of_range": "error",
        "missing_courtyard": "ignore",
        "missing_footprint": "warning",
        "net_conflict": "warning",
        "npth_inside_courtyard": "ignore",
        "padstack": "error",
        "pth_inside_courtyard": "ignore",
        "shorting_items": "error",
        "silk_over_copper": "warning",
        "silk_overlap": "warning",
        "skew_out_of_range": "error",
        "through_hole_pad_without_hole": "error",
        "too_many_vias": "error",
        "track_dangling": "warning",
        "track_width": "error",
        "tracks_crossing": "error",
        "unconnected_items": "error",
        "unresolved_variable": "error",
        "via_dangling": "warning",
        "zone_has_empty_net": "error",
        "zones_intersect": "error"
      },
      "rule_severitieslegacy_courtyards_overlap": true,
      "rule_severitieslegacy_no_courtyard_defined": false,
      "rules": {
        "allow_blind_buried_vias": false,
        "allow_microvias": false,
        "max_error": 0.005,
        "min_clearance": 0.0,
        "min_copper_edge_clearance": 0.024999999999999998,
        "min_hole_clearance": 0.25,
        "min_hole_to_hole": 0.25,
        "min_microvia_diameter": 0.6,
        "min_microvia_drill": 0.09999999999999999,
        "min_silk_clearance": 0.0,
        "min_through_hole_diameter": 0.19999999999999998,
        "min_track_width": 0.125,
        "min_via_annular_width": 0.049999999999999996,
        "min_via_diameter": 0.6,
        "use_height_for_length_calcs": true
      },
      "track_widths": [
        0.0,
        0.125,
        0.15,
        0.155,
        0.18,
        0.2,
        0.23,
        0.25,
        0.3,
        0.4,
        0.5,
        1.0
      ],
      "via_dimensions": [
        {
          "diameter": 0.0,
          "drill": 0.0
        },
        {
          "diameter": 0.6,
          "drill": 0.25
        }
      ],
      "zones_allow_external_fillets": false,
      "zones_use_no_outline": true
    },
    "layer_presets": []
  },
  "boards": [],
  "cvpcb": {
    "equivalence_files": []
  },
  "erc": {
    "erc_exclusions": [],
    "meta": {
      "version": 0
    },
    "pin_map": [
      [
        0,
        0,
        0,
        0,
        0,
        0,
        1,
        0,
        0,
        0,
        0,
        2
      ],
      [
        0,
        2,
        0,
        1,
        0,
        0,
        1,
        0,
        2,
        2,
        2,
        2
      ],
      [
        0,
        0,
        0,
        0,
        0,
        0,
        1,
        0,
        1,
        0,
        1,
        2
      ],
      [
        0,
        1,
        0,
        0,
        0,
        0,
        1,
        1,
        2,
        1,
        1,
        2
      ],
      [
        0,
        0,
        0,
        0,
        0,
        0,
        1,
        0,
        0,
        0,
        0,
        2
      ],
      [
        0,
        0,
        0,
        0,
        0,
        0,
        0,
        0,
        0,
        0,
        0,
        2
      ],
      [
        1,
        1,
        1,
        1,
        1,
        0,
        1,
        1,
        1,
        1,
        1,
        2
      ],
      [
        0,
        0,
        0,
        1,
        0,
        0,
        1,
        0,
        0,
        0,
        0,
        2
      ],
      [
        0,
        2,
        1,
        2,
        0,
        0,
        1,
        0,
        2,
        2,
        2,
        2
      ],
      [
        0,
        2,
        0,
        1,
        0,
        0,
        1,
        0,
        2,
        0,
        0,
        2
      ],
      [
        0,
        2,
        1,
        1,
        0,
        0,
        1,
        0,
        2,
        0,
        0,
        2
      ],
      [
        2,
        2,
        2,
        2,
        2,
        2,
        2,
        2,
        2,
        2,
        2,
        2
      ]
    ],
    "rule_severities": {
      "bus_definition_conflict": "error",
      "bus_entry_needed": "error",
      "bus_label_syntax": "error",
      "bus_to_bus_conflict": "error",
      "bus_to_net_conflict": "error",
      "different_unit_footprint": "error",
      "different_unit_net": "error",
      "duplicate_reference": "error",
      "duplicate_sheet_names": "error",
      "extra_units": "error",
      "global_label_dangling": "warning",
      "hier_label_mismatch": "error",
      "label_dangling": "error",
      "lib_symbol_issues": "warning",
      "multiple_net_names": "warning",
      "net_not_bus_member": "warning",
      "no_connect_connected": "ignore",
      "no_connect_dangling": "warning",
      "pin_not_connected": "error",
      "pin_not_driven": "error",
      "pin_to_pin": "ignore",
      "power_pin_not_driven": "error",
      "similar_labels": "warning",
      "unannotated": "error",
      "unit_value_mismatch": "error",
      "unresolved_variable": "error",
      "wire_dangling": "error"
    }
  },
  "libraries": {
    "pinned_footprint_libs": [],
    "pinned_symbol_libs": []
  },
  "meta": {
    "filename": "sa800u-baseboard-hw.kicad_pro",
    "version": 1
  },
  "net_settings": {
    "classes": [
      {
        "bus_width": 12.0,
        "clearance": 0.125,
        "diff_pair_gap": 0.125,
        "diff_pair_via_gap": 0.25,
        "diff_pair_width": 0.125,
        "line_style": 0,
        "microvia_diameter": 0.6,
        "microvia_drill": 0.25,
        "name": "Default",
        "pcb_color": "rgba(0, 0, 0, 0.000)",
        "schematic_color": "rgba(0, 0, 0, 0.000)",
        "track_width": 0.125,
        "via_diameter": 0.6,
        "via_drill": 0.25,
        "wire_width": 6.0
      },
      {
        "bus_width": 12.0,
        "clearance": 0.125,
        "diff_pair_gap": 0.125,
        "diff_pair_via_gap": 0.25,
        "diff_pair_width": 0.125,
        "line_style": 0,
        "microvia_diameter": 0.6,
        "microvia_drill": 0.25,
        "name": "SE50_inner",
        "nets": [],
        "pcb_color": "rgba(0, 0, 0, 0.000)",
        "schematic_color": "rgba(0, 0, 0, 0.000)",
        "track_width": 0.162,
        "via_diameter": 0.6,
        "via_drill": 0.25,
        "wire_width": 6.0
      },
      {
        "bus_width": 12.0,
        "clearance": 0.125,
        "diff_pair_gap": 0.125,
        "diff_pair_via_gap": 0.25,
        "diff_pair_width": 0.125,
        "line_style": 0,
        "microvia_diameter": 0.6,
        "microvia_drill": 0.25,
        "name": "SE50_outer",
        "nets": [
          "/Camera Interface/CCI0_I2C_SCL_3V3",
          "/Camera Interface/CCI0_I2C_SDA_3V3",
          "/Camera Interface/CCI1_I2C_SCL_3V3",
          "/Camera Interface/CCI1_I2C_SDA_3V3",
          "/HDMI converter/I2C_ADDR",
          "/LCM/TP_I2C_SCL_3V3",
          "/LCM/TP_I2C_SDA_3V3",
          "/Other Interfaces/SD_CLK_R",
          "/Other Interfaces/SD_CMD_R",
          "/Other Interfaces/SD_DATA0_R",
          "/Other Interfaces/SD_DATA1_R",
          "/Other Interfaces/SD_DATA2_R",
          "/Other Interfaces/SD_DATA3_R",
          "/Other Interfaces/SD_DET_R",
          "/Other Interfaces/SD_VDD_R",
          "/USB-C Interface /USB2_CC1",
          "/USB-C Interface /USB2_CC2",
          "/USB-PD/PD_CC1",
          "/USB-PD/PD_CC2",
          "CCI0_I2C_SCL",
          "CCI0_I2C_SDA",
          "CCI1_I2C_SCL",
          "CCI1_I2C_SDA",
          "I2C10_SCL",
          "I2C10_SDA",
          "I2C4_SCL",
          "I2C4_SDA",
          "SD_CLK",
          "SD_CMD",
          "SD_DATA0",
          "SD_DATA1",
          "SD_DATA2",
          "SD_DATA3",
          "SD_DET",
          "SD_LDO21A",
          "TP_I2C_SCL",
          "TP_I2C_SDA",
          "USB_CC1",
          "USB_CC2"
        ],
        "pcb_color": "rgba(0, 0, 0, 0.000)",
        "schematic_color": "rgba(0, 0, 0, 0.000)",
        "track_width": 0.182,
        "via_diameter": 0.6,
        "via_drill": 0.25,
        "wire_width": 6.0
      },
      {
        "bus_width": 12.0,
        "clearance": 0.125,
        "diff_pair_gap": 0.2,
        "diff_pair_via_gap": 0.25,
        "diff_pair_width": 0.125,
        "line_style": 0,
        "microvia_diameter": 0.6,
        "microvia_drill": 0.25,
        "name": "Z100_inner",
        "nets": [
          "/Camera Interface/CSI0_CLK_FFC_N",
          "/Camera Interface/CSI0_CLK_FFC_P",
          "/Camera Interface/CSI0_LN0_FFC_N",
          "/Camera Interface/CSI0_LN0_FFC_P",
          "/Camera Interface/CSI0_LN1_FFC_N",
          "/Camera Interface/CSI0_LN1_FFC_P",
          "/Camera Interface/CSI0_LN2_FFC_N",
          "/Camera Interface/CSI0_LN2_FFC_P",
          "/Camera Interface/CSI0_LN3_FFC_N",
          "/Camera Interface/CSI0_LN3_FFC_P",
          "/Camera Interface/CSI1_CLK_FFC_N",
          "/Camera Interface/CSI1_CLK_FFC_P",
          "/Camera Interface/CSI1_LN0_FFC_N",
          "/Camera Interface/CSI1_LN0_FFC_P",
          "/Camera Interface/CSI1_LN1_FFC_N",
          "/Camera Interface/CSI1_LN1_FFC_P",
          "/Camera Interface/CSI1_LN2_FFC_N",
          "/Camera Interface/CSI1_LN2_FFC_P",
          "/Camera Interface/CSI1_LN3_FFC_N",
          "/Camera Interface/CSI1_LN3_FFC_P",
          "CSI0_CLK_N",
          "CSI0_CLK_P",
          "CSI0_LN0_N",
          "CSI0_LN0_P",
          "CSI0_LN1_N",
          "CSI0_LN1_P",
          "CSI0_LN2_N",
          "CSI0_LN2_P",
          "CSI0_LN3_N",
          "CSI0_LN3_P",
          "CSI1_CLK_N",
          "CSI1_CLK_P",
          "CSI1_LN0_N",
          "CSI1_LN0_P",
          "CSI1_LN1_N",
          "CSI1_LN1_P",
          "CSI1_LN2_N",
          "CSI1_LN2_P",
          "CSI1_LN3_N",
          "CSI1_LN3_P"
        ],
        "pcb_color": "rgba(0, 0, 0, 0.000)",
        "schematic_color": "rgba(0, 0, 0, 0.000)",
        "track_width": 0.162,
        "via_diameter": 0.6,
        "via_drill": 0.25,
        "wire_width": 6.0
      },
      {
        "bus_width": 12.0,
        "clearance": 0.125,
        "diff_pair_gap": 0.125,
        "diff_pair_via_gap": 0.25,
        "diff_pair_width": 0.125,
        "line_style": 0,
        "microvia_diameter": 0.6,
        "microvia_drill": 0.25,
        "name": "Z100_outer",
        "nets": [
          "/Ethernet Controller/LAN0_MDI0_N",
          "/Ethernet Controller/LAN0_MDI0_P",
          "/Ethernet Controller/LAN0_MDI1_N",
          "/Ethernet Controller/LAN0_MDI1_P",
          "/Ethernet Controller/LAN0_MDI2_N",
          "/Ethernet Controller/LAN0_MDI2_P",
          "/Ethernet Controller/LAN0_MDI3_N",
          "/Ethernet Controller/LAN0_MDI3_P",
          "/LCM/DSI_CLK_L_N",
          "/LCM/DSI_CLK_L_P",
          "/LCM/DSI_LN0_L_N",
          "/LCM/DSI_LN0_L_P",
          "/LCM/DSI_LN1_L_N",
          "/LCM/DSI_LN1_L_P",
          "/LCM/DSI_LN2_L_N",
          "/LCM/DSI_LN2_L_P",
          "/LCM/DSI_LN3_L_N",
          "/LCM/DSI_LN3_L_P",
          "DSI0_CLK_N",
          "DSI0_CLK_P",
          "DSI0_LN0_N",
          "DSI0_LN0_P",
          "DSI0_LN1_N",
          "DSI0_LN1_P",
          "DSI0_LN2_N",
          "DSI0_LN2_P",
          "DSI0_LN3_N",
          "DSI0_LN3_P",
          "DSI1_CLK_N",
          "DSI1_CLK_P",
          "DSI1_LN0_N",
          "DSI1_LN0_P",
          "DSI1_LN1_N",
          "DSI1_LN1_P",
          "DSI1_LN2_N",
          "DSI1_LN2_P",
          "DSI1_LN3_N",
          "DSI1_LN3_P"
        ],
        "pcb_color": "rgba(0, 0, 0, 0.000)",
        "schematic_color": "rgba(0, 0, 0, 0.000)",
        "track_width": 0.182,
        "via_diameter": 0.6,
        "via_drill": 0.25,
        "wire_width": 6.0
      },
      {
        "bus_width": 12.0,
        "clearance": 0.125,
        "diff_pair_gap": 0.125,
        "diff_pair_via_gap": 0.25,
        "diff_pair_width": 0.14,
        "line_style": 0,
        "microvia_diameter": 0.6,
        "microvia_drill": 0.25,
        "name": "Z85_inner",
        "nets": [],
        "pcb_color": "rgba(0, 0, 0, 0.000)",
        "schematic_color": "rgba(0, 0, 0, 0.000)",
        "track_width": 0.233,
        "via_diameter": 0.6,
        "via_drill": 0.25,
        "wire_width": 6.0
      },
      {
        "bus_width": 12.0,
        "clearance": 0.125,
        "diff_pair_gap": 0.125,
        "diff_pair_via_gap": 0.25,
        "diff_pair_width": 0.17,
        "line_style": 0,
        "microvia_diameter": 0.6,
        "microvia_drill": 0.25,
        "name": "Z85_outer",
        "nets": [
          "/Ethernet Controller/PCIE1_RX_C_N",
          "/Ethernet Controller/PCIE1_RX_C_P",
          "/M2/C_PCIE0_TX0_N",
          "/M2/C_PCIE0_TX0_P",
          "PCIE0_CLKREQ_N",
          "PCIE0_REFCLK_N",
          "PCIE0_REFCLK_P",
          "PCIE0_RST_N",
          "PCIE0_RX_N",
          "PCIE0_RX_P",
          "PCIE0_TX_N",
          "PCIE0_TX_P",
          "PCIE0_WAKE_N",
          "PCIE1_CLKREQ_N",
          "PCIE1_REFCLK_N",
          "PCIE1_REFCLK_P",
          "PCIE1_RST_N",
          "PCIE1_RX_N",
          "PCIE1_RX_P",
          "PCIE1_TX_N",
          "PCIE1_TX_P",
          "PCIE1_WAKE_N"
        ],
        "pcb_color": "rgba(0, 0, 0, 0.000)",
        "schematic_color": "rgba(0, 0, 0, 0.000)",
        "track_width": 0.21,
        "via_diameter": 0.6,
        "via_drill": 0.25,
        "wire_width": 6.0
      },
      {
        "bus_width": 12.0,
        "clearance": 0.125,
        "diff_pair_gap": 0.125,
        "diff_pair_via_gap": 0.25,
        "diff_pair_width": 0.125,
        "line_style": 0,
        "microvia_diameter": 0.6,
        "microvia_drill": 0.25,
        "name": "Z90_inner",
        "nets": [],
        "pcb_color": "rgba(0, 0, 0, 0.000)",
        "schematic_color": "rgba(0, 0, 0, 0.000)",
        "track_width": 0.193,
        "via_diameter": 0.6,
        "via_drill": 0.25,
        "wire_width": 6.0
      },
      {
        "bus_width": 12.0,
        "clearance": 0.125,
        "diff_pair_gap": 0.125,
        "diff_pair_via_gap": 0.25,
        "diff_pair_width": 0.155,
        "line_style": 0,
        "microvia_diameter": 0.6,
        "microvia_drill": 0.25,
        "name": "Z90_outer",
        "nets": [
          "/USB-C Interface /DBG_USB_D_N",
          "/USB-C Interface /DBG_USB_D_P",
          "/USB-C Interface /USB1C_RX0_C_N",
          "/USB-C Interface /USB1C_RX0_C_P",
          "/USB-C Interface /USB1C_RX1_C_N",
          "/USB-C Interface /USB1C_RX1_C_P",
          "/USB-C Interface /USB1C_TX0_C_N",
          "/USB-C Interface /USB1C_TX0_C_P",
          "/USB-C Interface /USB1C_TX1_C_N",
          "/USB-C Interface /USB1C_TX1_C_P",
          "/USB-C Interface /USB1_SBU_N",
          "/USB-C Interface /USB1_SBU_P",
          "/USB-C Interface /USB2C_RX1_C_N",
          "/USB-C Interface /USB2C_RX1_C_P",
          "/USB-C Interface /USB2C_RX1_N",
          "/USB-C Interface /USB2C_RX1_P",
          "/USB-C Interface /USB2C_RX2_C_N",
          "/USB-C Interface /USB2C_RX2_C_P",
          "/USB-C Interface /USB2C_RX2_N",
          "/USB-C Interface /USB2C_RX2_P",
          "/USB-C Interface /USB2C_TX1_C_N",
          "/USB-C Interface /USB2C_TX1_C_P",
          "/USB-C Interface /USB2C_TX1_N",
          "/USB-C Interface /USB2C_TX1_P",
          "/USB-C Interface /USB2C_TX2_C_N",
          "/USB-C Interface /USB2C_TX2_C_P",
          "/USB-C Interface /USB2C_TX2_N",
          "/USB-C Interface /USB2C_TX2_P",
          "/USB-C Interface /USB_SBU_NP_N",
          "/USB-C Interface /USB_SBU_NP_P",
          "EDP_AUX_N",
          "EDP_AUX_P",
          "USB1_D_N",
          "USB1_D_P",
          "USB1_SS_RX0_N",
          "USB1_SS_RX0_P",
          "USB1_SS_RX1_N",
          "USB1_SS_RX1_P",
          "USB1_SS_TX0_N",
          "USB1_SS_TX0_P",
          "USB1_SS_TX1_N",
          "USB1_SS_TX1_P",
          "USB2C_HS_D_N",
          "USB2C_HS_D_P",
          "USB2_SS_RX_N",
          "USB2_SS_RX_P",
          "USB2_SS_TX_N",
          "USB2_SS_TX_P"
        ],
        "pcb_color": "rgba(0, 0, 0, 0.000)",
        "schematic_color": "rgba(0, 0, 0, 0.000)",
        "track_width": 0.215,
        "via_diameter": 0.6,
        "via_drill": 0.25,
        "wire_width": 6.0
      }
    ],
    "meta": {
      "version": 2
    },
    "net_colors": null
  },
  "pcbnew": {
    "last_paths": {
      "gencad": "",
      "idf": "",
      "netlist": "sa800u-baseboard-hw.net",
      "specctra_dsn": "",
      "step": "",
      "vrml": ""
    },
    "page_layout_descr_file": ""
  },
  "schematic": {
    "annotate_start_num": 0,
    "drawing": {
      "default_line_thickness": 6.0,
      "default_text_size": 50.0,
      "field_names": [],
      "intersheets_ref_own_page": false,
      "intersheets_ref_prefix": "",
      "intersheets_ref_short": false,
      "intersheets_ref_show": false,
      "intersheets_ref_suffix": "",
      "junction_size_choice": 3,
      "label_size_ratio": 0.25,
      "pin_symbol_size": 0.0,
      "text_offset_ratio": 0.08
    },
    "legacy_lib_dir": "",
    "legacy_lib_list": [],
    "meta": {
      "version": 1
    },
    "net_format_name": "Pcbnew",
    "ngspice": {
      "fix_include_paths": true,
      "fix_passive_vals": false,
      "meta": {
        "version": 0
      },
      "model_mode": 0,
      "workbook_filename": ""
    },
    "page_layout_descr_file": "",
    "plot_directory": "",
    "spice_adjust_passive_values": false,
    "spice_external_command": "spice \"%I\"",
    "subpart_first_id": 65,
    "subpart_id_separator": 0
  },
  "sheets": [
    [
      "",
      ""
    ],
    [
      "",
      "PoE"
    ],
    [
      "",
      "Camera Interface"
    ],
    [
      "",
      "Ethernet Controller"
    ],
    [
      "",
      "M2"
    ],
    [
      "",
      "HDMI converter"
    ],
    [
      "",
      "Other Interfaces"
    ],
    [
      "",
      "USB-C Interface "
    ],
    [
      "",
      "PSU"
    ],
    [
      "",
      "USB-PD"
    ],
    [
      "",
      "LCM"
    ],
    [
      "",
      "SoM"
    ]
  ],
  "text_variables": {}
}
